(kicad_pcb
	(version 20260206)
	(generator "pcbnew")
	(generator_version "10.0")
	(general
		(thickness 1.6)
		(legacy_teardrops no)
	)
	(paper "A4")
	(title_block
		(title "timecard-production-celestica-r4006 — R4006-B0001-02_R01.brd")
		(comment 1 "Time Appliance Project (Time Card) / footprints 1110-1113 of 1113")
	)
	(layers
		(0 "F.Cu" signal "TOP")
		(4 "In1.Cu" signal "L02_GND1")
		(6 "In2.Cu" signal "L03_SIG1")
		(8 "In3.Cu" signal "L04_GND2")
		(10 "In4.Cu" signal "L05_VCC1")
		(12 "In5.Cu" signal "L06_VCC2")
		(14 "In6.Cu" signal "L07_GND3")
		(16 "In7.Cu" signal "L08_SIG2")
		(18 "In8.Cu" signal "L09_GND4")
		(2 "B.Cu" signal "BOTTOM")
		(9 "F.Adhes" user "F.Adhesive")
		(11 "B.Adhes" user "B.Adhesive")
		(13 "F.Paste" user "Package Geometry/Pastemask Top")
		(15 "B.Paste" user "Package Geometry/Pastemask Bottom")
		(5 "F.SilkS" user "Ref Des/Silkscreen Top")
		(7 "B.SilkS" user "Ref Des/Silkscreen Bottom")
		(1 "F.Mask" user "Board Geometry/Soldermask Top")
		(3 "B.Mask" user "Board Geometry/Soldermask Bottom")
		(17 "Dwgs.User" user "User.Drawings")
		(19 "Cmts.User" user "User.Comments")
		(21 "Eco1.User" user "User.Eco1")
		(23 "Eco2.User" user "User.Eco2")
		(25 "Edge.Cuts" user "Board Geometry/Outline")
		(27 "Margin" user)
		(31 "F.CrtYd" user "Package Geometry/Place Bound Top")
		(29 "B.CrtYd" user "Package Geometry/Place Bound Bottom")
		(35 "F.Fab" user "Ref Des/Assembly Top")
		(33 "B.Fab" user "Ref Des/Assembly Bottom")
	)
	(footprint ""
		(layer "B.Cu")
		(at 111.847122 -42.323004 90)
		(property "Reference" "C201"
			(at -1.141984 -42.018712 270)
			(unlocked yes)
			(layer "B.SilkS")
			(effects
				(font
					(size 0.635 0.4064)
					(thickness 0.1524)
				)
				(justify mirror)
			)
		)
		(property "Value" "VAL*"
			(at 0 3.718306 90)
			(unlocked yes)
			(layer "B.Fab")
			(hide yes)
			(effects
				(font
					(size 0.7874 0.5842)
					(thickness 0.127)
				)
				(justify mirror)
			)
		)
		(property "Device Type" "CAPACITOR-G105-0B104-CK,0.1UF,A"
			(at 0 1.432306 90)
			(unlocked yes)
			(layer "B.Fab")
			(hide yes)
			(effects
				(font
					(size 0.7874 0.5842)
					(thickness 0.127)
				)
				(justify mirror)
			)
		)
		(property "User Part Number" "PARTNUM*"
			(at 0 2.575306 90)
			(unlocked yes)
			(layer "Cmts.User")
			(hide yes)
			(effects
				(font
					(size 0.7874 0.5842)
					(thickness 0.127)
				)
				(justify mirror)
			)
		)
		(property "Tolerance" "TOL*"
			(at 0 4.861306 90)
			(unlocked yes)
			(layer "Cmts.User")
			(hide yes)
			(effects
				(font
					(size 0.7874 0.5842)
					(thickness 0.127)
				)
				(justify mirror)
			)
		)
		(duplicate_pad_numbers_are_jumpers no)
		(fp_line
			(start 0.970026 -0.4699)
			(end -0.970026 -0.4699)
			(stroke
				(width 0.1)
				(type default)
			)
			(layer "B.SilkS")
		)
		(fp_line
			(start -0.970026 -0.4699)
			(end -0.970026 0.4699)
			(stroke
				(width 0.1)
				(type default)
			)
			(layer "B.SilkS")
		)
		(fp_line
			(start 0.970026 0.4699)
			(end 0.970026 -0.4699)
			(stroke
				(width 0.1)
				(type default)
			)
			(layer "B.SilkS")
		)
		(fp_line
			(start -0.970026 0.4699)
			(end 0.970026 0.4699)
			(stroke
				(width 0.1)
				(type default)
			)
			(layer "B.SilkS")
		)
		(fp_poly
			(pts
				(xy 0.970026 0.4699) (xy -0.970026 0.4699) (xy -0.970026 -0.4699) (xy 0.970026 -0.4699)
			)
			(stroke
				(width 0)
				(type default)
			)
			(fill no)
			(layer "B.CrtYd")
		)
		(fp_line
			(start 0.508 -0.3048)
			(end -0.508 -0.3048)
			(stroke
				(width 0.1)
				(type default)
			)
			(layer "B.Fab")
		)
		(fp_line
			(start -0.508 -0.3048)
			(end -0.508 0.3048)
			(stroke
				(width 0.1)
				(type default)
			)
			(layer "B.Fab")
		)
		(fp_line
			(start 0.508 0.3048)
			(end 0.508 -0.3048)
			(stroke
				(width 0.1)
				(type default)
			)
			(layer "B.Fab")
		)
		(fp_line
			(start -0.508 0.3048)
			(end 0.508 0.3048)
			(stroke
				(width 0.1)
				(type default)
			)
			(layer "B.Fab")
		)
		(pad "1" smd circle
			(at 0.500126 0 270)
			(size 0.635 0.635)
			(layers "B.Cu" "B.Mask" "B.Paste")
			(net "XP1R0V_FPGA_VCCINT")
		)
		(pad "2" smd circle
			(at -0.500126 0 270)
			(size 0.635 0.635)
			(layers "B.Cu" "B.Mask" "B.Paste")
			(net "SG")
		)
	)
	(footprint ""
		(layer "B.Cu")
		(at 113.347246 -42.82313 180)
		(property "Reference" "C138"
			(at 41.909746 -1.24968 0)
			(unlocked yes)
			(layer "B.SilkS")
			(effects
				(font
					(size 0.635 0.4064)
					(thickness 0.1524)
				)
				(justify mirror)
			)
		)
		(property "Value" "VAL*"
			(at 0 3.718306 180)
			(unlocked yes)
			(layer "B.Fab")
			(hide yes)
			(effects
				(font
					(size 0.7874 0.5842)
					(thickness 0.127)
				)
				(justify mirror)
			)
		)
		(property "Tolerance" "TOL*"
			(at 0 4.861306 180)
			(unlocked yes)
			(layer "Cmts.User")
			(hide yes)
			(effects
				(font
					(size 0.7874 0.5842)
					(thickness 0.127)
				)
				(justify mirror)
			)
		)
		(property "User Part Number" "PARTNUM*"
			(at 0 2.575306 180)
			(unlocked yes)
			(layer "Cmts.User")
			(hide yes)
			(effects
				(font
					(size 0.7874 0.5842)
					(thickness 0.127)
				)
				(justify mirror)
			)
		)
		(property "Device Type" "CAPACITOR-G105-0F475-BM,4.7UF,A"
			(at 0 1.432306 180)
			(unlocked yes)
			(layer "B.Fab")
			(hide yes)
			(effects
				(font
					(size 0.7874 0.5842)
					(thickness 0.127)
				)
				(justify mirror)
			)
		)
		(duplicate_pad_numbers_are_jumpers no)
		(fp_line
			(start 0.970026 0.4699)
			(end 0.970026 -0.4699)
			(stroke
				(width 0.1)
				(type default)
			)
			(layer "B.SilkS")
		)
		(fp_line
			(start 0.970026 -0.4699)
			(end -0.970026 -0.4699)
			(stroke
				(width 0.1)
				(type default)
			)
			(layer "B.SilkS")
		)
		(fp_line
			(start -0.970026 0.4699)
			(end 0.970026 0.4699)
			(stroke
				(width 0.1)
				(type default)
			)
			(layer "B.SilkS")
		)
		(fp_line
			(start -0.970026 -0.4699)
			(end -0.970026 0.4699)
			(stroke
				(width 0.1)
				(type default)
			)
			(layer "B.SilkS")
		)
		(fp_poly
			(pts
				(xy 0.970026 0.4699) (xy -0.970026 0.4699) (xy -0.970026 -0.4699) (xy 0.970026 -0.4699)
			)
			(stroke
				(width 0)
				(type default)
			)
			(fill no)
			(layer "B.CrtYd")
		)
		(fp_line
			(start 0.508 0.3048)
			(end 0.508 -0.3048)
			(stroke
				(width 0.1)
				(type default)
			)
			(layer "B.Fab")
		)
		(fp_line
			(start 0.508 -0.3048)
			(end -0.508 -0.3048)
			(stroke
				(width 0.1)
				(type default)
			)
			(layer "B.Fab")
		)
		(fp_line
			(start -0.508 0.3048)
			(end 0.508 0.3048)
			(stroke
				(width 0.1)
				(type default)
			)
			(layer "B.Fab")
		)
		(fp_line
			(start -0.508 -0.3048)
			(end -0.508 0.3048)
			(stroke
				(width 0.1)
				(type default)
			)
			(layer "B.Fab")
		)
		(pad "1" smd circle
			(at 0.500126 0)
			(size 0.635 0.635)
			(layers "B.Cu" "B.Mask" "B.Paste")
			(net "XP1R8V_FPGA_VCCAUX")
		)
		(pad "2" smd circle
			(at -0.500126 0)
			(size 0.635 0.635)
			(layers "B.Cu" "B.Mask" "B.Paste")
			(net "SG")
		)
	)
	(footprint ""
		(layer "B.Cu")
		(at 13.462 -37.211 90)
		(property "Reference" "R492"
			(at -1.524 1.73863 270)
			(unlocked yes)
			(layer "B.SilkS")
			(effects
				(font
					(size 0.7874 0.5842)
					(thickness 0.1524)
				)
				(justify mirror)
			)
		)
		(property "Value" "VAL*"
			(at -0.02032 2.13233 90)
			(unlocked yes)
			(layer "B.Fab")
			(hide yes)
			(effects
				(font
					(size 0.7874 0.5842)
					(thickness 0.1524)
				)
				(justify mirror)
			)
		)
		(property "Tolerance" "TOL*"
			(at -0.044704 3.05435 90)
			(unlocked yes)
			(layer "Cmts.User")
			(hide yes)
			(effects
				(font
					(size 0.7874 0.5842)
					(thickness 0.1524)
				)
				(justify mirror)
			)
		)
		(property "User Part Number" "PARTNUM*"
			(at -0.02032 4.024884 90)
			(unlocked yes)
			(layer "Cmts.User")
			(hide yes)
			(effects
				(font
					(size 0.7874 0.5842)
					(thickness 0.1524)
				)
				(justify mirror)
			)
		)
		(property "Device Type" "RESISTOR-G155-100R0-J0,0OHM,-"
			(at -0.008382 1.210564 90)
			(unlocked yes)
			(layer "B.Fab")
			(hide yes)
			(effects
				(font
					(size 0.7874 0.5842)
					(thickness 0.1524)
				)
				(justify mirror)
			)
		)
		(duplicate_pad_numbers_are_jumpers no)
		(fp_line
			(start 1.143 -0.5588)
			(end 1.143 0.5588)
			(stroke
				(width 0.1)
				(type default)
			)
			(layer "B.SilkS")
		)
		(fp_line
			(start -1.143 -0.5588)
			(end 1.143 -0.5588)
			(stroke
				(width 0.1)
				(type default)
			)
			(layer "B.SilkS")
		)
		(fp_line
			(start 1.143 0.5588)
			(end -1.143 0.5588)
			(stroke
				(width 0.1)
				(type default)
			)
			(layer "B.SilkS")
		)
		(fp_line
			(start -1.143 0.5588)
			(end -1.143 -0.5588)
			(stroke
				(width 0.1)
				(type default)
			)
			(layer "B.SilkS")
		)
		(fp_poly
			(pts
				(xy 1.143 0.5588) (xy -1.143 0.5588) (xy -1.143 -0.5588) (xy 1.143 -0.5588)
			)
			(stroke
				(width 0)
				(type default)
			)
			(fill no)
			(layer "B.CrtYd")
		)
		(fp_line
			(start 0.508 -0.3048)
			(end 0.508 0.3048)
			(stroke
				(width 0.1)
				(type default)
			)
			(layer "B.Fab")
		)
		(fp_line
			(start -0.508 -0.3048)
			(end 0.508 -0.3048)
			(stroke
				(width 0.1)
				(type default)
			)
			(layer "B.Fab")
		)
		(fp_line
			(start 0.508 0.3048)
			(end -0.508 0.3048)
			(stroke
				(width 0.1)
				(type default)
			)
			(layer "B.Fab")
		)
		(fp_line
			(start -0.508 0.3048)
			(end -0.508 -0.3048)
			(stroke
				(width 0.1)
				(type default)
			)
			(layer "B.Fab")
		)
		(pad "1" smd rect
			(at 0.5334 0 270)
			(size 0.7112 0.6096)
			(layers "B.Cu" "B.Mask" "B.Paste")
			(net "UNNAMED_12_CAPACITOR_I318_2")
		)
		(pad "2" smd rect
			(at -0.5334 0 270)
			(size 0.7112 0.6096)
			(layers "B.Cu" "B.Mask" "B.Paste")
			(net "UNNAMED_12_74HCT2G125DPTSSOP8_I")
		)
		(zone
			(layer "B.Cu")
			(hatch none 0.5)
			(connect_pads
				(clearance 0)
			)
			(min_thickness 0.25)
			(keepout
				(tracks allowed)
				(vias not_allowed)
				(pads allowed)
				(copperpour not_allowed)
				(footprints allowed)
			)
			(placement
				(enabled no)
				(sheetname "")
			)
			(fill
				(thermal_gap 0.5)
				(thermal_bridge_width 0.5)
				(island_removal_mode 0)
			)
			(polygon
				(pts
					(xy 13.7668 -37.2872) (xy 13.1572 -37.2872) (xy 13.1572 -37.1348) (xy 13.7668 -37.1348)
				)
			)
		)
		(zone
			(layer "B.Cu")
			(hatch none 0.5)
			(connect_pads
				(clearance 0)
			)
			(min_thickness 0.25)
			(keepout
				(tracks not_allowed)
				(vias allowed)
				(pads allowed)
				(copperpour not_allowed)
				(footprints allowed)
			)
			(placement
				(enabled no)
				(sheetname "")
			)
			(fill
				(thermal_gap 0.5)
				(thermal_bridge_width 0.5)
				(island_removal_mode 0)
			)
			(polygon
				(pts
					(xy 13.7668 -37.2872) (xy 13.1572 -37.2872) (xy 13.1572 -37.1348) (xy 13.7668 -37.1348)
				)
			)
		)
	)
	(footprint ""
		(layer "B.Cu")
		(at 107.188 -44.45)
		(property "Reference" "C219"
			(at -43.307 1.63195 0)
			(unlocked yes)
			(layer "B.SilkS")
			(effects
				(font
					(size 0.635 0.4064)
					(thickness 0.1524)
				)
				(justify mirror)
			)
		)
		(property "Value" "VAL*"
			(at -0.0762 2.067306 0)
			(unlocked yes)
			(layer "B.Fab")
			(hide yes)
			(effects
				(font
					(size 0.7874 0.5842)
					(thickness 0.1524)
				)
				(justify mirror)
			)
		)
		(property "Device Type" "CAPACITOR-G105-0B104-CK,0.1UF,A"
			(at -0.0508 1.127506 0)
			(unlocked yes)
			(layer "B.Fab")
			(hide yes)
			(effects
				(font
					(size 0.7874 0.5842)
					(thickness 0.1524)
				)
				(justify mirror)
			)
		)
		(property "User Part Number" "PARTNUM*"
			(at -0.1016 4.023106 0)
			(unlocked yes)
			(layer "Cmts.User")
			(hide yes)
			(effects
				(font
					(size 0.7874 0.5842)
					(thickness 0.1524)
				)
				(justify mirror)
			)
		)
		(property "Tolerance" "TOL*"
			(at -0.0762 3.032506 0)
			(unlocked yes)
			(layer "Cmts.User")
			(hide yes)
			(effects
				(font
					(size 0.7874 0.5842)
					(thickness 0.1524)
				)
				(justify mirror)
			)
		)
		(duplicate_pad_numbers_are_jumpers no)
		(fp_line
			(start -1.143 -0.5588)
			(end 1.143 -0.5588)
			(stroke
				(width 0.1)
				(type default)
			)
			(layer "B.SilkS")
		)
		(fp_line
			(start -1.143 0.5588)
			(end -1.143 -0.5588)
			(stroke
				(width 0.1)
				(type default)
			)
			(layer "B.SilkS")
		)
		(fp_line
			(start 1.143 -0.5588)
			(end 1.143 0.5588)
			(stroke
				(width 0.1)
				(type default)
			)
			(layer "B.SilkS")
		)
		(fp_line
			(start 1.143 0.5588)
			(end -1.143 0.5588)
			(stroke
				(width 0.1)
				(type default)
			)
			(layer "B.SilkS")
		)
		(fp_rect
			(start -1.143 0.5588)
			(end 1.143 -0.5588)
			(stroke
				(width 0)
				(type default)
			)
			(fill no)
			(layer "B.CrtYd")
		)
		(fp_line
			(start -0.508 -0.3048)
			(end 0.508 -0.3048)
			(stroke
				(width 0.1)
				(type default)
			)
			(layer "B.Fab")
		)
		(fp_line
			(start -0.508 0.3048)
			(end -0.508 -0.3048)
			(stroke
				(width 0.1)
				(type default)
			)
			(layer "B.Fab")
		)
		(fp_line
			(start 0.508 -0.3048)
			(end 0.508 0.3048)
			(stroke
				(width 0.1)
				(type default)
			)
			(layer "B.Fab")
		)
		(fp_line
			(start 0.508 0.3048)
			(end -0.508 0.3048)
			(stroke
				(width 0.1)
				(type default)
			)
			(layer "B.Fab")
		)
		(pad "1" smd rect
			(at 0.5334 0 180)
			(size 0.7112 0.6096)
			(layers "B.Cu" "B.Mask" "B.Paste")
			(net "XP1R8V_FPGA_VCCAUX")
		)
		(pad "2" smd rect
			(at -0.5334 0 180)
			(size 0.7112 0.6096)
			(layers "B.Cu" "B.Mask" "B.Paste")
			(net "SG")
		)
		(zone
			(layer "B.Cu")
			(hatch none 0.5)
			(connect_pads
				(clearance 0)
			)
			(min_thickness 0.25)
			(keepout
				(tracks allowed)
				(vias not_allowed)
				(pads allowed)
				(copperpour not_allowed)
				(footprints allowed)
			)
			(placement
				(enabled no)
				(sheetname "")
			)
			(fill
				(thermal_gap 0.5)
				(thermal_bridge_width 0.5)
				(island_removal_mode 0)
			)
			(polygon
				(pts
					(xy 107.1118 -44.1452) (xy 107.2642 -44.1452) (xy 107.2642 -44.7548) (xy 107.1118 -44.7548)
				)
			)
		)
	)
)
